# T6G (Grand Teton) — schematic netlist excerpt (pin names and nets, part order shuffled) for the footprints in the layout excerpt that follows; sources: Cadence DE-HDL packaged netlist, KiCad conversion of 04192023_DAF0TMB3IC0_F0TG_MB_C_brd_V02_OCP.brd

PU300  MAX15090BEWIT  MAX15090BEWI+T IC  pkg BGA28_0-5_3-525X2-065  page 152
  ISENSE  = P12V_SCM_SENSE
  VCC  = P12V_SCM_VCC
  IN_A3  = P12V_AUX
  OUT_A4  = P12V_SCM_R
  IN_A5  = P12V_AUX
  GATE  = P12V_SCM_GATE
  CDLY  = GND
  CB  = P12V_SCM_CB
  GND_B2  = GND
  IN_B3  = P12V_AUX
  OUT_B4  = P12V_SCM_R
  IN_B5  = P12V_AUX
  OUT_B6  = P12V_SCM_R
  \en#\  = GND
  GND_C1  = GND
  GND_C2  = GND
  IN_C3  = P12V_AUX
  OUT_C4  = P12V_SCM_R
  IN_C5  = P12V_AUX
  OUT_C6  = P12V_SCM_R
  \fault#\  = P12V_SCM_FAULT_N
  REG  = P12V_SCM_REG
  UV  = P12V_SCM_UV
  OV  = P12V_SCM_OV
  OUT_D4  = P12V_SCM_R
  IN_D5  = P12V_AUX
  OUT_D6  = P12V_SCM_R
  PG  = P12V_SCM_PWRGD

C6582  Q_CAP_DIFFBUS  DIFF BUS_0.22UF 6.3V 20% X6S  pkg C0201  page 297 : \1\ = P5E_CPU0_P2_TX_BUF_C_DN<8> ; \2\ = P5E_CPU0_P2_TX_BUF_DN<8>

(kicad_pcb
	(version 20260206)
	(generator "pcbnew")
	(generator_version "10.0")
	(general
		(thickness 1.6)
		(legacy_teardrops no)
	)
	(paper "A4")
	(title_block
		(title "04192023_DAF0TMB3IC0_F0TG_MB_C_brd_V02_OCP.brd")
		(comment 1 "Grand Teton / footprints 1001-1002 of 8354")
	)
	(layers
		(0 "F.Cu" signal "TOP")
		(4 "In1.Cu" signal "GND")
		(6 "In2.Cu" signal "IN1")
		(8 "In3.Cu" signal "GND1")
		(10 "In4.Cu" signal "IN2")
		(12 "In5.Cu" signal "GND2")
		(14 "In6.Cu" signal "IN3")
		(16 "In7.Cu" signal "GND3")
		(18 "In8.Cu" signal "VCC")
		(20 "In9.Cu" signal "VCC1")
		(22 "In10.Cu" signal "GND4")
		(24 "In11.Cu" signal "IN4")
		(26 "In12.Cu" signal "GND5")
		(28 "In13.Cu" signal "IN5")
		(30 "In14.Cu" signal "GND6")
		(32 "In15.Cu" signal "IN6")
		(34 "In16.Cu" signal "GND7")
		(2 "B.Cu" signal "BOTTOM")
		(9 "F.Adhes" user "F.Adhesive")
		(11 "B.Adhes" user "B.Adhesive")
		(13 "F.Paste" user "Package Geometry/Pastemask Top")
		(15 "B.Paste" user "Package Geometry/Pastemask Bottom")
		(5 "F.SilkS" user "Ref Des/Silkscreen Top")
		(7 "B.SilkS" user "Ref Des/Silkscreen Bottom")
		(1 "F.Mask" user "Board Geometry/Soldermask Top")
		(3 "B.Mask" user "Board Geometry/Soldermask Bottom")
		(17 "Dwgs.User" user "User.Drawings")
		(19 "Cmts.User" user "User.Comments")
		(21 "Eco1.User" user "User.Eco1")
		(23 "Eco2.User" user "User.Eco2")
		(25 "Edge.Cuts" user "Board Geometry/Outline")
		(27 "Margin" user)
		(31 "F.CrtYd" user "Package Geometry/Place Bound Top")
		(29 "B.CrtYd" user "Package Geometry/Place Bound Bottom")
		(35 "F.Fab" user "Ref Des/Assembly Top")
		(33 "B.Fab" user "Ref Des/Assembly Bottom")
	)
	(footprint ""
		(layer "F.Cu")
		(at 189.738762 -25.643332)
		(property "Reference" "PU300"
			(at 3.987546 -1.268222 0)
			(unlocked yes)
			(layer "F.SilkS")
			(effects
				(font
					(size 0.7874 0.5842)
					(thickness 0.1524)
				)
				(justify left)
			)
		)
		(property "Value" ""
			(at 0 0 0)
			(layer "F.Fab")
			(effects
				(font
					(size 1.27 1.27)
				)
			)
		)
		(duplicate_pad_numbers_are_jumpers no)
		(fp_line
			(start -1.774952 -1.039876)
			(end -1.774952 1.039876)
			(stroke
				(width 0.1524)
				(type default)
			)
			(layer "F.SilkS")
		)
		(fp_line
			(start -1.774952 1.039876)
			(end 1.774952 1.039876)
			(stroke
				(width 0.1524)
				(type default)
			)
			(layer "F.SilkS")
		)
		(fp_line
			(start 1.774952 -1.039876)
			(end -1.774952 -1.039876)
			(stroke
				(width 0.1524)
				(type default)
			)
			(layer "F.SilkS")
		)
		(fp_line
			(start 1.774952 1.039876)
			(end 1.774952 -1.039876)
			(stroke
				(width 0.1524)
				(type default)
			)
			(layer "F.SilkS")
		)
		(fp_poly
			(pts
				(xy -0.999998 -1.801876) (xy -0.999998 -1.039876) (xy -1.769872 -1.039876) (xy -1.769872 -0.249936)
				(xy -2.531872 -0.249936) (xy -2.531872 -1.801876)
			)
			(stroke
				(width 0)
				(type default)
			)
			(fill yes)
			(layer "F.SilkS")
		)
		(fp_line
			(start -1.769872 -1.039876)
			(end -1.769872 1.039876)
			(stroke
				(width 0.1)
				(type default)
			)
			(layer "F.Fab")
		)
		(fp_line
			(start -1.769872 1.039876)
			(end 1.769872 1.039876)
			(stroke
				(width 0.1)
				(type default)
			)
			(layer "F.Fab")
		)
		(fp_line
			(start 1.769872 -1.039876)
			(end -1.769872 -1.039876)
			(stroke
				(width 0.1)
				(type default)
			)
			(layer "F.Fab")
		)
		(fp_line
			(start 1.769872 1.039876)
			(end 1.769872 -1.039876)
			(stroke
				(width 0.1)
				(type default)
			)
			(layer "F.Fab")
		)
		(fp_poly
			(pts
				(xy -1.769872 -1.039876) (xy -0.999998 -1.039876) (xy -0.999998 -1.801876) (xy -2.531872 -1.801876)
				(xy -2.531872 -0.249936) (xy -1.769872 -0.249936)
			)
			(stroke
				(width 0)
				(type default)
			)
			(fill yes)
			(layer "F.Fab")
		)
		(pad "A1" smd circle
			(at -1.500124 -0.750062)
			(size 0.2286 0.2286)
			(layers "F.Cu" "F.Mask" "F.Paste")
			(net "P12V_SCM_SENSE")
		)
		(pad "A2" smd circle
			(at -0.999998 -0.750062)
			(size 0.2286 0.2286)
			(layers "F.Cu" "F.Mask" "F.Paste")
			(net "P12V_SCM_VCC")
		)
		(pad "A3" smd circle
			(at -0.499872 -0.750062)
			(size 0.2286 0.2286)
			(layers "F.Cu" "F.Mask" "F.Paste")
			(net "P12V_AUX")
		)
		(pad "A4" smd circle
			(at 0 -0.750062)
			(size 0.2286 0.2286)
			(layers "F.Cu" "F.Mask" "F.Paste")
			(net "P12V_SCM_R")
		)
		(pad "A5" smd circle
			(at 0.499872 -0.750062)
			(size 0.2286 0.2286)
			(layers "F.Cu" "F.Mask" "F.Paste")
			(net "P12V_AUX")
		)
		(pad "A6" smd circle
			(at 0.999998 -0.750062)
			(size 0.2286 0.2286)
			(layers "F.Cu" "F.Mask" "F.Paste")
			(net "P12V_SCM_GATE")
		)
		(pad "A7" smd circle
			(at 1.500124 -0.750062)
			(size 0.2286 0.2286)
			(layers "F.Cu" "F.Mask" "F.Paste")
			(net "GND")
		)
		(pad "B1" smd circle
			(at -1.500124 -0.249936)
			(size 0.2286 0.2286)
			(layers "F.Cu" "F.Mask" "F.Paste")
			(net "P12V_SCM_CB")
		)
		(pad "B2" smd circle
			(at -0.999998 -0.249936)
			(size 0.2286 0.2286)
			(layers "F.Cu" "F.Mask" "F.Paste")
			(net "GND")
		)
		(pad "B3" smd circle
			(at -0.499872 -0.249936)
			(size 0.2286 0.2286)
			(layers "F.Cu" "F.Mask" "F.Paste")
			(net "P12V_AUX")
		)
		(pad "B4" smd circle
			(at 0 -0.249936)
			(size 0.2286 0.2286)
			(layers "F.Cu" "F.Mask" "F.Paste")
			(net "P12V_SCM_R")
		)
		(pad "B5" smd circle
			(at 0.499872 -0.249936)
			(size 0.2286 0.2286)
			(layers "F.Cu" "F.Mask" "F.Paste")
			(net "P12V_AUX")
		)
		(pad "B6" smd circle
			(at 0.999998 -0.249936)
			(size 0.2286 0.2286)
			(layers "F.Cu" "F.Mask" "F.Paste")
			(net "P12V_SCM_R")
		)
		(pad "B7" smd circle
			(at 1.500124 -0.249936)
			(size 0.2286 0.2286)
			(layers "F.Cu" "F.Mask" "F.Paste")
			(net "GND")
		)
		(pad "C1" smd circle
			(at -1.500124 0.249936)
			(size 0.2286 0.2286)
			(layers "F.Cu" "F.Mask" "F.Paste")
			(net "GND")
		)
		(pad "C2" smd circle
			(at -0.999998 0.249936)
			(size 0.2286 0.2286)
			(layers "F.Cu" "F.Mask" "F.Paste")
			(net "GND")
		)
		(pad "C3" smd circle
			(at -0.499872 0.249936)
			(size 0.2286 0.2286)
			(layers "F.Cu" "F.Mask" "F.Paste")
			(net "P12V_AUX")
		)
		(pad "C4" smd circle
			(at 0 0.249936)
			(size 0.2286 0.2286)
			(layers "F.Cu" "F.Mask" "F.Paste")
			(net "P12V_SCM_R")
		)
		(pad "C5" smd circle
			(at 0.499872 0.249936)
			(size 0.2286 0.2286)
			(layers "F.Cu" "F.Mask" "F.Paste")
			(net "P12V_AUX")
		)
		(pad "C6" smd circle
			(at 0.999998 0.249936)
			(size 0.2286 0.2286)
			(layers "F.Cu" "F.Mask" "F.Paste")
			(net "P12V_SCM_R")
		)
		(pad "C7" smd circle
			(at 1.500124 0.249936)
			(size 0.2286 0.2286)
			(layers "F.Cu" "F.Mask" "F.Paste")
			(net "P12V_SCM_FAULT_N")
		)
		(pad "D1" smd circle
			(at -1.500124 0.750062)
			(size 0.2286 0.2286)
			(layers "F.Cu" "F.Mask" "F.Paste")
			(net "P12V_SCM_REG")
		)
		(pad "D2" smd circle
			(at -0.999998 0.750062)
			(size 0.2286 0.2286)
			(layers "F.Cu" "F.Mask" "F.Paste")
			(net "P12V_SCM_UV")
		)
		(pad "D3" smd circle
			(at -0.499872 0.750062)
			(size 0.2286 0.2286)
			(layers "F.Cu" "F.Mask" "F.Paste")
			(net "P12V_SCM_OV")
		)
		(pad "D4" smd circle
			(at 0 0.750062)
			(size 0.2286 0.2286)
			(layers "F.Cu" "F.Mask" "F.Paste")
			(net "P12V_SCM_R")
		)
		(pad "D5" smd circle
			(at 0.499872 0.750062)
			(size 0.2286 0.2286)
			(layers "F.Cu" "F.Mask" "F.Paste")
			(net "P12V_AUX")
		)
		(pad "D6" smd circle
			(at 0.999998 0.750062)
			(size 0.2286 0.2286)
			(layers "F.Cu" "F.Mask" "F.Paste")
			(net "P12V_SCM_R")
		)
		(pad "D7" smd circle
			(at 1.500124 0.750062)
			(size 0.2286 0.2286)
			(layers "F.Cu" "F.Mask" "F.Paste")
			(net "P12V_SCM_PWRGD")
		)
	)
	(footprint ""
		(layer "F.Cu")
		(at 395.374622 -416.899344 -90)
		(property "Reference" "C6582"
			(at 0 0 270)
			(layer "F.SilkS")
			(hide yes)
			(effects
				(font
					(size 1.27 1.27)
				)
			)
		)
		(property "Value" ""
			(at 0 0 270)
			(layer "F.Fab")
			(effects
				(font
					(size 1.27 1.27)
				)
			)
		)
		(duplicate_pad_numbers_are_jumpers no)
		(fp_line
			(start -0.299974 0.150114)
			(end -0.299974 -0.150114)
			(stroke
				(width 0.1)
				(type default)
			)
			(layer "F.Fab")
		)
		(fp_line
			(start 0.299974 0.150114)
			(end -0.299974 0.150114)
			(stroke
				(width 0.1)
				(type default)
			)
			(layer "F.Fab")
		)
		(fp_line
			(start -0.299974 -0.150114)
			(end 0.299974 -0.150114)
			(stroke
				(width 0.1)
				(type default)
			)
			(layer "F.Fab")
		)
		(fp_line
			(start 0.299974 -0.150114)
			(end 0.299974 0.150114)
			(stroke
				(width 0.1)
				(type default)
			)
			(layer "F.Fab")
		)
		(pad "1" smd rect
			(at -0.2667 0 270)
			(size 0.3048 0.381)
			(layers "F.Cu" "F.Mask" "F.Paste")
			(net "P5E_CPU0_P2_TX_BUF_C_DN<8>")
		)
		(pad "2" smd rect
			(at 0.2667 0 270)
			(size 0.3048 0.381)
			(layers "F.Cu" "F.Mask" "F.Paste")
			(net "P5E_CPU0_P2_TX_BUF_DN<8>")
		)
	)
)
